(kicad_pcb
	(version 20260206)
	(generator "pcbnew")
	(generator_version "10.0")
	(general
		(thickness 1.6)
		(legacy_teardrops no)
	)
	(paper "A4")
	(title_block
		(title "Wiwynn_Tioga_Pass_MB.brd")
		(comment 1 "Tioga Pass / footprints 2691-2697 of 4770")
	)
	(layers
		(0 "F.Cu" signal "TOP")
		(4 "In1.Cu" signal "L2GND")
		(6 "In2.Cu" signal "L3")
		(8 "In3.Cu" signal "L4GND")
		(10 "In4.Cu" signal "L5")
		(12 "In5.Cu" signal "L6GND")
		(14 "In6.Cu" signal "L7VCC")
		(16 "In7.Cu" signal "L8VCC")
		(18 "In8.Cu" signal "L9GND")
		(20 "In9.Cu" signal "L10")
		(22 "In10.Cu" signal "L11GND")
		(24 "In11.Cu" signal "L12")
		(26 "In12.Cu" signal "L13GND")
		(2 "B.Cu" signal "BOTTOM")
		(9 "F.Adhes" user "F.Adhesive")
		(11 "B.Adhes" user "B.Adhesive")
		(13 "F.Paste" user "Package Geometry/Pastemask Top")
		(15 "B.Paste" user "Package Geometry/Pastemask Bottom")
		(5 "F.SilkS" user "Ref Des/Silkscreen Top")
		(7 "B.SilkS" user "Ref Des/Silkscreen Bottom")
		(1 "F.Mask" user "Board Geometry/Soldermask Top")
		(3 "B.Mask" user "Board Geometry/Soldermask Bottom")
		(17 "Dwgs.User" user "User.Drawings")
		(19 "Cmts.User" user "User.Comments")
		(21 "Eco1.User" user "User.Eco1")
		(23 "Eco2.User" user "User.Eco2")
		(25 "Edge.Cuts" user "Board Geometry/Outline")
		(27 "Margin" user)
		(31 "F.CrtYd" user "Package Geometry/Place Bound Top")
		(29 "B.CrtYd" user "Package Geometry/Place Bound Bottom")
		(35 "F.Fab" user "Ref Des/Assembly Top")
		(33 "B.Fab" user "Ref Des/Assembly Bottom")
	)
	(footprint ""
		(layer "B.Cu")
		(at 330.5048 -9.1186 90)
		(property "Reference" "Q4U1"
			(at -0.76327 4.7752 0)
			(unlocked yes)
			(layer "B.SilkS")
			(effects
				(font
					(size 0.7874 0.5842)
					(thickness 0.1524)
				)
				(justify left mirror)
			)
		)
		(property "Value" ""
			(at 0 0 90)
			(layer "B.Fab")
			(effects
				(font
					(size 1.27 1.27)
				)
				(justify mirror)
			)
		)
		(duplicate_pad_numbers_are_jumpers no)
		(fp_circle
			(center 0.508 -0.7874)
			(end 0.508 -0.6604)
			(stroke
				(width 0.254)
				(type default)
			)
			(fill no)
			(layer "B.SilkS")
		)
		(fp_poly
			(pts
				(xy -0.2159 1.7526) (xy -1.5621 1.7526) (xy -1.5621 -0.4572) (xy -0.2159 -0.4572)
			)
			(stroke
				(width 0)
				(type default)
			)
			(fill no)
			(layer "B.CrtYd")
		)
		(fp_line
			(start -0.2159 -0.45466)
			(end -0.2159 1.75514)
			(stroke
				(width 0.1)
				(type default)
			)
			(layer "B.Fab")
		)
		(fp_line
			(start -1.5621 -0.45466)
			(end -0.2159 -0.45466)
			(stroke
				(width 0.1)
				(type default)
			)
			(layer "B.Fab")
		)
		(fp_line
			(start -0.2159 1.75514)
			(end -1.5621 1.75514)
			(stroke
				(width 0.1)
				(type default)
			)
			(layer "B.Fab")
		)
		(fp_line
			(start -1.5621 1.75514)
			(end -1.5621 -0.45466)
			(stroke
				(width 0.1)
				(type default)
			)
			(layer "B.Fab")
		)
		(fp_circle
			(center 0.508 -0.7874)
			(end 0.508 -0.6604)
			(stroke
				(width 0.254)
				(type default)
			)
			(fill no)
			(layer "B.Fab")
		)
		(pad "1" smd rect
			(at 0 0 270)
			(size 1.016 0.381)
			(layers "B.Cu" "B.Mask" "B.Paste")
			(net "GND")
		)
		(pad "2" smd rect
			(at 0 0.65024 270)
			(size 1.016 0.381)
			(layers "B.Cu" "B.Mask" "B.Paste")
			(net "FM_DIMM_EVENT_COD_N")
		)
		(pad "3" smd rect
			(at 0 1.30048 270)
			(size 1.016 0.381)
			(layers "B.Cu" "B.Mask" "B.Paste")
			(net "FM_MEM_THERM_EVENT_LVT3_N")
		)
		(pad "4" smd rect
			(at -1.778 1.30048 270)
			(size 1.016 0.381)
			(layers "B.Cu" "B.Mask" "B.Paste")
			(net "GND")
		)
		(pad "5" smd rect
			(at -1.778 0.65024 270)
			(size 1.016 0.381)
			(layers "B.Cu" "B.Mask" "B.Paste")
			(net "FM_DIMM_EVENT_FET")
		)
		(pad "6" smd rect
			(at -1.778 0 270)
			(size 1.016 0.381)
			(layers "B.Cu" "B.Mask" "B.Paste")
			(net "FM_DIMM_EVENT_FET")
		)
		(zone
			(layer "B.Cu")
			(hatch none 0.5)
			(connect_pads
				(clearance 0)
			)
			(min_thickness 0.25)
			(keepout
				(tracks allowed)
				(vias not_allowed)
				(pads allowed)
				(copperpour not_allowed)
				(footprints allowed)
			)
			(placement
				(enabled no)
				(sheetname "")
			)
			(fill
				(thermal_gap 0.5)
				(thermal_bridge_width 0.5)
				(island_removal_mode 0)
			)
			(polygon
				(pts
					(xy 330.3143 -9.6266) (xy 330.3143 -8.6106) (xy 332.0034 -8.6106) (xy 332.0034 -9.6266)
				)
			)
		)
		(zone
			(layer "B.Cu")
			(hatch none 0.5)
			(connect_pads
				(clearance 0)
			)
			(min_thickness 0.25)
			(keepout
				(tracks allowed)
				(vias not_allowed)
				(pads allowed)
				(copperpour not_allowed)
				(footprints allowed)
			)
			(placement
				(enabled no)
				(sheetname "")
			)
			(fill
				(thermal_gap 0.5)
				(thermal_bridge_width 0.5)
				(island_removal_mode 0)
			)
			(polygon
				(pts
					(xy 330.3143 -7.8486) (xy 330.3143 -6.8326) (xy 332.0034 -6.8326) (xy 332.0034 -7.8486)
				)
			)
		)
	)
	(footprint ""
		(layer "B.Cu")
		(at 252.1585 -149.8092 -90)
		(property "Reference" "C5G61"
			(at -1.14681 0.76708 0)
			(unlocked yes)
			(layer "B.SilkS")
			(effects
				(font
					(size 0.7874 0.5842)
					(thickness 0.1524)
				)
				(justify mirror)
			)
		)
		(property "Value" ""
			(at 0 0 90)
			(layer "B.Fab")
			(effects
				(font
					(size 1.27 1.27)
				)
				(justify mirror)
			)
		)
		(duplicate_pad_numbers_are_jumpers no)
		(fp_rect
			(start 0.4953 1.6002)
			(end -0.4953 -0.2032)
			(stroke
				(width 0)
				(type default)
			)
			(fill no)
			(layer "B.CrtYd")
		)
		(fp_line
			(start -0.4953 1.6002)
			(end 0.4953 1.6002)
			(stroke
				(width 0.1)
				(type default)
			)
			(layer "B.Fab")
		)
		(fp_line
			(start 0.4953 1.6002)
			(end 0.4953 -0.2032)
			(stroke
				(width 0.1)
				(type default)
			)
			(layer "B.Fab")
		)
		(fp_line
			(start -0.4953 -0.2032)
			(end -0.4953 1.6002)
			(stroke
				(width 0.1)
				(type default)
			)
			(layer "B.Fab")
		)
		(fp_line
			(start 0.4953 -0.2032)
			(end -0.4953 -0.2032)
			(stroke
				(width 0.1)
				(type default)
			)
			(layer "B.Fab")
		)
		(pad "1" smd rect
			(at 0 0 90)
			(size 0.762 0.889)
			(layers "B.Cu" "B.Mask" "B.Paste")
			(net "PVDDQ_DEF")
		)
		(pad "2" smd rect
			(at 0 1.397 90)
			(size 0.762 0.889)
			(layers "B.Cu" "B.Mask" "B.Paste")
			(net "GND")
		)
		(zone
			(layer "B.Cu")
			(hatch none 0.5)
			(connect_pads
				(clearance 0)
			)
			(min_thickness 0.25)
			(keepout
				(tracks not_allowed)
				(vias allowed)
				(pads allowed)
				(copperpour not_allowed)
				(footprints allowed)
			)
			(placement
				(enabled no)
				(sheetname "")
			)
			(fill
				(thermal_gap 0.5)
				(thermal_bridge_width 0.5)
				(island_removal_mode 0)
			)
			(polygon
				(pts
					(xy 251.206 -149.4282) (xy 251.714 -149.4282) (xy 251.714 -150.1902) (xy 251.206 -150.1902)
				)
			)
		)
	)
	(footprint ""
		(layer "B.Cu")
		(at 408.559 0.2794 -90)
		(property "Reference" "C2U27"
			(at 0 0 90)
			(layer "B.SilkS")
			(hide yes)
			(effects
				(font
					(size 1.27 1.27)
				)
				(justify mirror)
			)
		)
		(property "Value" ""
			(at 0 0 90)
			(layer "B.Fab")
			(effects
				(font
					(size 1.27 1.27)
				)
				(justify mirror)
			)
		)
		(duplicate_pad_numbers_are_jumpers no)
		(fp_poly
			(pts
				(xy -0.3048 -0.1016) (xy -0.3048 0.9906) (xy 0.3048 0.9906) (xy 0.3048 -0.1016)
			)
			(stroke
				(width 0)
				(type default)
			)
			(fill no)
			(layer "B.CrtYd")
		)
		(fp_line
			(start -0.3048 0.9906)
			(end -0.3048 -0.1016)
			(stroke
				(width 0.1)
				(type default)
			)
			(layer "B.Fab")
		)
		(fp_line
			(start 0.3048 0.9906)
			(end -0.3048 0.9906)
			(stroke
				(width 0.1)
				(type default)
			)
			(layer "B.Fab")
		)
		(fp_line
			(start -0.3048 -0.1016)
			(end 0.3048 -0.1016)
			(stroke
				(width 0.1)
				(type default)
			)
			(layer "B.Fab")
		)
		(fp_line
			(start 0.3048 -0.1016)
			(end 0.3048 0.9906)
			(stroke
				(width 0.1)
				(type default)
			)
			(layer "B.Fab")
		)
		(pad "1" smd rect
			(at 0 0 90)
			(size 0.508 0.508)
			(layers "B.Cu" "B.Mask" "B.Paste")
			(net "P3V3_STBY")
		)
		(pad "2" smd rect
			(at 0 0.889 90)
			(size 0.508 0.508)
			(layers "B.Cu" "B.Mask" "B.Paste")
			(net "GND")
		)
		(zone
			(layer "B.Cu")
			(hatch none 0.5)
			(connect_pads
				(clearance 0)
			)
			(min_thickness 0.25)
			(keepout
				(tracks not_allowed)
				(vias allowed)
				(pads allowed)
				(copperpour not_allowed)
				(footprints allowed)
			)
			(placement
				(enabled no)
				(sheetname "")
			)
			(fill
				(thermal_gap 0.5)
				(thermal_bridge_width 0.5)
				(island_removal_mode 0)
			)
			(polygon
				(pts
					(xy 407.924 0.5334) (xy 407.924 0.0254) (xy 408.305 0.0254) (xy 408.305 0.5334)
				)
			)
		)
		(zone
			(layer "B.Cu")
			(hatch none 0.5)
			(connect_pads
				(clearance 0)
			)
			(min_thickness 0.25)
			(keepout
				(tracks allowed)
				(vias not_allowed)
				(pads allowed)
				(copperpour not_allowed)
				(footprints allowed)
			)
			(placement
				(enabled no)
				(sheetname "")
			)
			(fill
				(thermal_gap 0.5)
				(thermal_bridge_width 0.5)
				(island_removal_mode 0)
			)
			(polygon
				(pts
					(xy 408.305 0.5334) (xy 408.305 0.0254) (xy 407.924 0.0254) (xy 407.924 0.5334)
				)
			)
		)
	)
	(footprint ""
		(layer "B.Cu")
		(at 401.5613 -37.1094 90)
		(property "Reference" "R2U13"
			(at 0 0 90)
			(layer "B.SilkS")
			(hide yes)
			(effects
				(font
					(size 1.27 1.27)
				)
				(justify mirror)
			)
		)
		(property "Value" ""
			(at 0 0 90)
			(layer "B.Fab")
			(effects
				(font
					(size 1.27 1.27)
				)
				(justify mirror)
			)
		)
		(duplicate_pad_numbers_are_jumpers no)
		(fp_poly
			(pts
				(xy 0.2794 -0.1016) (xy -0.2794 -0.1016) (xy -0.2794 0.9906) (xy 0.2794 0.9906)
			)
			(stroke
				(width 0)
				(type default)
			)
			(fill no)
			(layer "B.CrtYd")
		)
		(fp_line
			(start 0.2794 -0.1016)
			(end 0.2794 0.9906)
			(stroke
				(width 0.1)
				(type default)
			)
			(layer "B.Fab")
		)
		(fp_line
			(start -0.2794 -0.1016)
			(end 0.2794 -0.1016)
			(stroke
				(width 0.1)
				(type default)
			)
			(layer "B.Fab")
		)
		(fp_line
			(start 0.2794 0.9906)
			(end -0.2794 0.9906)
			(stroke
				(width 0.1)
				(type default)
			)
			(layer "B.Fab")
		)
		(fp_line
			(start -0.2794 0.9906)
			(end -0.2794 -0.1016)
			(stroke
				(width 0.1)
				(type default)
			)
			(layer "B.Fab")
		)
		(pad "1" smd rect
			(at 0 0 270)
			(size 0.508 0.508)
			(layers "B.Cu" "B.Mask" "B.Paste")
			(net "P3V3_STBY")
		)
		(pad "2" smd rect
			(at 0 0.889 270)
			(size 0.508 0.508)
			(layers "B.Cu" "B.Mask" "B.Paste")
			(net "SMB_OCP_FRU_STBY_LVC3_SDA_R")
		)
		(zone
			(layer "B.Cu")
			(hatch none 0.5)
			(connect_pads
				(clearance 0)
			)
			(min_thickness 0.25)
			(keepout
				(tracks allowed)
				(vias not_allowed)
				(pads allowed)
				(copperpour not_allowed)
				(footprints allowed)
			)
			(placement
				(enabled no)
				(sheetname "")
			)
			(fill
				(thermal_gap 0.5)
				(thermal_bridge_width 0.5)
				(island_removal_mode 0)
			)
			(polygon
				(pts
					(xy 401.8153 -37.3634) (xy 401.8153 -36.8554) (xy 402.1963 -36.8554) (xy 402.1963 -37.3634)
				)
			)
		)
		(zone
			(layer "B.Cu")
			(hatch none 0.5)
			(connect_pads
				(clearance 0)
			)
			(min_thickness 0.25)
			(keepout
				(tracks not_allowed)
				(vias allowed)
				(pads allowed)
				(copperpour not_allowed)
				(footprints allowed)
			)
			(placement
				(enabled no)
				(sheetname "")
			)
			(fill
				(thermal_gap 0.5)
				(thermal_bridge_width 0.5)
				(island_removal_mode 0)
			)
			(polygon
				(pts
					(xy 402.1963 -37.3634) (xy 402.1963 -36.8554) (xy 401.8153 -36.8554) (xy 401.8153 -37.3634)
				)
			)
		)
	)
	(footprint ""
		(layer "B.Cu")
		(at 417.6522 -74.0537)
		(property "Reference" "R9F3"
			(at 0 0 0)
			(layer "B.SilkS")
			(hide yes)
			(effects
				(font
					(size 1.27 1.27)
				)
				(justify mirror)
			)
		)
		(property "Value" ""
			(at 0 0 0)
			(layer "B.Fab")
			(effects
				(font
					(size 1.27 1.27)
				)
				(justify mirror)
			)
		)
		(duplicate_pad_numbers_are_jumpers no)
		(fp_poly
			(pts
				(xy 0.2794 -0.1016) (xy -0.2794 -0.1016) (xy -0.2794 0.9906) (xy 0.2794 0.9906)
			)
			(stroke
				(width 0)
				(type default)
			)
			(fill no)
			(layer "B.CrtYd")
		)
		(fp_line
			(start -0.2794 -0.1016)
			(end 0.2794 -0.1016)
			(stroke
				(width 0.1)
				(type default)
			)
			(layer "B.Fab")
		)
		(fp_line
			(start -0.2794 0.9906)
			(end -0.2794 -0.1016)
			(stroke
				(width 0.1)
				(type default)
			)
			(layer "B.Fab")
		)
		(fp_line
			(start 0.2794 -0.1016)
			(end 0.2794 0.9906)
			(stroke
				(width 0.1)
				(type default)
			)
			(layer "B.Fab")
		)
		(fp_line
			(start 0.2794 0.9906)
			(end -0.2794 0.9906)
			(stroke
				(width 0.1)
				(type default)
			)
			(layer "B.Fab")
		)
		(pad "1" smd rect
			(at 0 0 180)
			(size 0.508 0.508)
			(layers "B.Cu" "B.Mask" "B.Paste")
			(net "P3V3_STBY")
		)
		(pad "2" smd rect
			(at 0 0.889 180)
			(size 0.508 0.508)
			(layers "B.Cu" "B.Mask" "B.Paste")
			(net "FM_FAST_PROCHOT_EN")
		)
		(zone
			(layer "B.Cu")
			(hatch none 0.5)
			(connect_pads
				(clearance 0)
			)
			(min_thickness 0.25)
			(keepout
				(tracks allowed)
				(vias not_allowed)
				(pads allowed)
				(copperpour not_allowed)
				(footprints allowed)
			)
			(placement
				(enabled no)
				(sheetname "")
			)
			(fill
				(thermal_gap 0.5)
				(thermal_bridge_width 0.5)
				(island_removal_mode 0)
			)
			(polygon
				(pts
					(xy 417.9062 -73.7997) (xy 417.3982 -73.7997) (xy 417.3982 -73.4187) (xy 417.9062 -73.4187)
				)
			)
		)
		(zone
			(layer "B.Cu")
			(hatch none 0.5)
			(connect_pads
				(clearance 0)
			)
			(min_thickness 0.25)
			(keepout
				(tracks not_allowed)
				(vias allowed)
				(pads allowed)
				(copperpour not_allowed)
				(footprints allowed)
			)
			(placement
				(enabled no)
				(sheetname "")
			)
			(fill
				(thermal_gap 0.5)
				(thermal_bridge_width 0.5)
				(island_removal_mode 0)
			)
			(polygon
				(pts
					(xy 417.9062 -73.4187) (xy 417.3982 -73.4187) (xy 417.3982 -73.7997) (xy 417.9062 -73.7997)
				)
			)
		)
	)
	(footprint ""
		(layer "B.Cu")
		(at 375.158 -82.169 90)
		(property "Reference" "R7D18"
			(at 0.8382 -0.67818 90)
			(unlocked yes)
			(layer "B.SilkS")
			(effects
				(font
					(size 0.4064 0.254)
					(thickness 0.1524)
				)
				(justify left mirror)
			)
		)
		(property "Value" ""
			(at 0 0 90)
			(layer "B.Fab")
			(effects
				(font
					(size 1.27 1.27)
				)
				(justify mirror)
			)
		)
		(duplicate_pad_numbers_are_jumpers no)
		(fp_poly
			(pts
				(xy 0.2794 -0.1016) (xy -0.2794 -0.1016) (xy -0.2794 0.9906) (xy 0.2794 0.9906)
			)
			(stroke
				(width 0)
				(type default)
			)
			(fill no)
			(layer "B.CrtYd")
		)
		(fp_line
			(start 0.2794 -0.1016)
			(end 0.2794 0.9906)
			(stroke
				(width 0.1)
				(type default)
			)
			(layer "B.Fab")
		)
		(fp_line
			(start -0.2794 -0.1016)
			(end 0.2794 -0.1016)
			(stroke
				(width 0.1)
				(type default)
			)
			(layer "B.Fab")
		)
		(fp_line
			(start 0.2794 0.9906)
			(end -0.2794 0.9906)
			(stroke
				(width 0.1)
				(type default)
			)
			(layer "B.Fab")
		)
		(fp_line
			(start -0.2794 0.9906)
			(end -0.2794 -0.1016)
			(stroke
				(width 0.1)
				(type default)
			)
			(layer "B.Fab")
		)
		(pad "1" smd rect
			(at 0 0 270)
			(size 0.508 0.508)
			(layers "B.Cu" "B.Mask" "B.Paste")
			(net "FM_THERMTRIP_DLY")
		)
		(pad "2" smd rect
			(at 0 0.889 270)
			(size 0.508 0.508)
			(layers "B.Cu" "B.Mask" "B.Paste")
			(net "FM_THERMTRIP_DLY_R")
		)
		(zone
			(layer "B.Cu")
			(hatch none 0.5)
			(connect_pads
				(clearance 0)
			)
			(min_thickness 0.25)
			(keepout
				(tracks allowed)
				(vias not_allowed)
				(pads allowed)
				(copperpour not_allowed)
				(footprints allowed)
			)
			(placement
				(enabled no)
				(sheetname "")
			)
			(fill
				(thermal_gap 0.5)
				(thermal_bridge_width 0.5)
				(island_removal_mode 0)
			)
			(polygon
				(pts
					(xy 375.412 -82.423) (xy 375.412 -81.915) (xy 375.793 -81.915) (xy 375.793 -82.423)
				)
			)
		)
		(zone
			(layer "B.Cu")
			(hatch none 0.5)
			(connect_pads
				(clearance 0)
			)
			(min_thickness 0.25)
			(keepout
				(tracks not_allowed)
				(vias allowed)
				(pads allowed)
				(copperpour not_allowed)
				(footprints allowed)
			)
			(placement
				(enabled no)
				(sheetname "")
			)
			(fill
				(thermal_gap 0.5)
				(thermal_bridge_width 0.5)
				(island_removal_mode 0)
			)
			(polygon
				(pts
					(xy 375.793 -82.423) (xy 375.793 -81.915) (xy 375.412 -81.915) (xy 375.412 -82.423)
				)
			)
		)
	)
	(footprint ""
		(layer "B.Cu")
		(at 193.092832 2.1336 -90)
		(property "Reference" "C6U18"
			(at 0 0 90)
			(layer "B.SilkS")
			(hide yes)
			(effects
				(font
					(size 1.27 1.27)
				)
				(justify mirror)
			)
		)
		(property "Value" ""
			(at 0 0 90)
			(layer "B.Fab")
			(effects
				(font
					(size 1.27 1.27)
				)
				(justify mirror)
			)
		)
		(duplicate_pad_numbers_are_jumpers no)
		(fp_rect
			(start -0.7239 1.9939)
			(end 0.7239 -0.2159)
			(stroke
				(width 0)
				(type default)
			)
			(fill no)
			(layer "B.CrtYd")
		)
		(fp_line
			(start -0.7239 1.9939)
			(end -0.7239 -0.2159)
			(stroke
				(width 0.1)
				(type default)
			)
			(layer "B.Fab")
		)
		(fp_line
			(start 0.7239 1.9939)
			(end -0.7239 1.9939)
			(stroke
				(width 0.1)
				(type default)
			)
			(layer "B.Fab")
		)
		(fp_line
			(start -0.7239 -0.2159)
			(end 0.7239 -0.2159)
			(stroke
				(width 0.1)
				(type default)
			)
			(layer "B.Fab")
		)
		(fp_line
			(start 0.7239 -0.2159)
			(end 0.7239 1.9939)
			(stroke
				(width 0.1)
				(type default)
			)
			(layer "B.Fab")
		)
		(pad "1" smd rect
			(at 0 0 90)
			(size 1.27 1.016)
			(layers "B.Cu" "B.Mask" "B.Paste")
			(net "P12V_NVDIMM_ABC")
		)
		(pad "2" smd rect
			(at 0 1.778 90)
			(size 1.27 1.016)
			(layers "B.Cu" "B.Mask" "B.Paste")
			(net "GND")
		)
		(zone
			(layer "B.Cu")
			(hatch none 0.5)
			(connect_pads
				(clearance 0)
			)
			(min_thickness 0.25)
			(keepout
				(tracks not_allowed)
				(vias allowed)
				(pads allowed)
				(copperpour not_allowed)
				(footprints allowed)
			)
			(placement
				(enabled no)
				(sheetname "")
			)
			(fill
				(thermal_gap 0.5)
				(thermal_bridge_width 0.5)
				(island_removal_mode 0)
			)
			(polygon
				(pts
					(xy 191.822832 1.4986) (xy 191.822832 2.7686) (xy 192.584832 2.7686) (xy 192.584832 1.4986)
				)
			)
		)
	)
)
